#ISCELL
  mstr_misc dns *
  *
#ISCELL
  pure_quanta quanta_title_block_c *
  *
#ISCELL
  pure_quanta_power universal_gnd *
  page330_i1
#ISCELL
  standard offpage *
  page330_i10
#ISCELL
  pure_quanta_power universal_gnd *
  page330_i11
#CELL
  pure_quanta q_res *
  page330_i12
#CELL
  pure_quanta q_res *
  page330_i13
#ISCELL
  pure_quanta_power universal_gnd *
  page330_i14
#CELL
  pure_quanta q_res *
  page330_i15
#ISCELL
  pure_quanta_power universal_power *
  page330_i16
#CELL
  pure_quanta q_res *
  page330_i17
#ISCELL
  pure_quanta_power universal_power *
  page330_i18
#ISCELL
  pure_quanta_power universal_gnd *
  page330_i19
#CELL
  pure_quanta q_res *
  page330_i2
#CELL
  pure_quanta q_res *
  page330_i20
#CELL
  pure_quanta mosfet_nch_dual *
  page330_i21
#CELL
  pure_quanta mosfet_nch_dual *
  page330_i22
#CELL
  pure_quanta q_res *
  page330_i23
#ISCELL
  pure_quanta_power universal_power *
  page330_i24
#ISCELL
  pure_quanta_power universal_gnd *
  page330_i25
#CELL
  pure_quanta q_res *
  page330_i26
#ISCELL
  pure_quanta_power universal_power *
  page330_i27
#ISCELL
  pure_quanta_power universal_gnd *
  page330_i28
#CELL
  pure_quanta mosfet_nch_dual *
  page330_i29
#CELL
  pure_quanta mosfet_nch_dual *
  page330_i3
#CELL
  pure_quanta mosfet_nch_dual *
  page330_i30
#CELL
  pure_quanta mosfet_nch_dual *
  page330_i31
#CELL
  pure_quanta q_res *
  page330_i32
#ISCELL
  pure_quanta_power universal_gnd *
  page330_i33
#ISCELL
  pure_quanta_power universal_power *
  page330_i34
#ISCELL
  pure_quanta_power universal_gnd *
  page330_i35
#CELL
  pure_quanta q_cap *
  page330_i36
#ISCELL
  standard offpage *
  page330_i37
#ISCELL
  standard offpage *
  page330_i38
#ISCELL
  standard offpage *
  page330_i39
#ISCELL
  pure_quanta_power universal_gnd *
  page330_i4
#ISCELL
  standard offpage *
  page330_i40
#ISCELL
  pure_quanta_power universal_gnd *
  page330_i41
#CELL
  pure_quanta q_cap *
  page330_i42
#ISCELL
  standard offpage *
  page330_i43
#ISCELL
  pure_quanta_power universal_gnd *
  page330_i44
#CELL
  pure_quanta q_cap *
  page330_i45
#ISCELL
  standard offpage *
  page330_i46
#ISCELL
  standard offpage *
  page330_i47
#ISCELL
  standard offpage *
  page330_i48
#ISCELL
  pure_quanta_power universal_gnd *
  page330_i49
#ISCELL
  pure_quanta_power universal_gnd *
  page330_i5
#CELL
  pure_quanta q_res *
  page330_i50
#CELL
  pure_quanta q_res *
  page330_i51
#CELL
  pure_quanta mosfet_nch_dual *
  page330_i52
#ISCELL
  pure_quanta_power universal_gnd *
  page330_i53
#ISCELL
  pure_quanta_power universal_power *
  page330_i54
#CELL
  pure_quanta q_res *
  page330_i55
#ISCELL
  pure_quanta_power universal_power *
  page330_i56
#CELL
  pure_quanta q_res *
  page330_i57
#ISCELL
  pure_quanta_power universal_power *
  page330_i58
#ISCELL
  standard offpage *
  page330_i59
#ISCELL
  standard offpage *
  page330_i6
#ISCELL
  pure_quanta_power universal_power *
  page330_i60
#CELL
  pure_quanta q_res *
  page330_i61
#ISCELL
  pure_quanta_power universal_power *
  page330_i62
#ISCELL
  pure_quanta_power universal_gnd *
  page330_i63
#CELL
  pure_quanta q_res *
  page330_i64
#CELL
  pure_quanta q_res *
  page330_i65
#CELL
  pure_quanta q_res *
  page330_i66
#CELL
  pure_quanta q_res *
  page330_i67
#ISCELL
  pure_quanta_power universal_gnd *
  page330_i68
#CELL
  pure_quanta q_res *
  page330_i69
#ISCELL
  standard offpage *
  page330_i7
#ISCELL
  pure_quanta_power universal_gnd *
  page330_i70
#CELL
  pure_quanta q_cap *
  page330_i71
#CELL
  pure_quanta q_res *
  page330_i72
#ISCELL
  pure_quanta_power universal_power *
  page330_i73
#ISCELL
  standard offpage *
  page330_i74
#CELL
  pure_quanta mosfet_nch_dual *
  page330_i75
#CELL
  pure_quanta q_res *
  page330_i8
#ISCELL
  pure_quanta_power universal_power *
  page330_i9
